# SCM (Grand Teton) — schematic parts with pin connectivity, parts 1–186 of 1428; source: Cadence DE-HDL packaged netlist (pstxprt.dat, pstxnet.dat, pstchip.dat)

C1  Q_CAP  4.7UF 25V 10% X6S  pkg C0603  page 20 : 1 = P1V2_AUX ; 2 = GND
C2  Q_CAP  1UF 25V 10% X6S  pkg C0402  page 20 : 1 = P1V2_AUX ; 2 = GND
C3  Q_CAP  1UF 25V 10% X6S  pkg C0402  page 20 : 1 = P1V2_AUX ; 2 = GND
C4  Q_CAP  1UF 25V 10% X6S  pkg C0402  page 20 : 1 = P1V2_AUX ; 2 = GND
C5  Q_CAP  1UF 25V 10% X6S  pkg C0402  page 20 : 1 = P1V2_AUX ; 2 = GND
C6  Q_CAP  0.1UF 25V 10% X7R  pkg 0402  page 20 : 1 = P2V5_AUX ; 2 = GND
C7  Q_CAP  0.1UF 25V 10% X7R  pkg 0402  page 20 : 1 = P1V2_AUX ; 2 = GND
C8  Q_CAP  0.1UF 25V 10% X7R  pkg 0402  page 20 : 1 = P2V5_AUX ; 2 = GND
C9  Q_CAP  100PF 50V 5% NPO  pkg 0402  page 20 : 1 = P1V2_AUX ; 2 = GND
C10  Q_CAP  0.1UF 25V 10% X7R  pkg 0402  page 20 : 1 = P0V6_DDR_VREF_AUX ; 2 = GND
C11  Q_CAP  0.1UF 25V 10% X7R  pkg 0402  page 31 : 1 = P3V3_AUX ; 2 = GND
C12  Q_CAP  0.22UF 16V 10% X7R  pkg 0402  page 20 : 1 = M_BMC_DDR4_MCLK_C ; 2 = GND
C13  Q_CAP  0.1UF 25V 10% X7R  pkg 0402  page 20 : 1 = P1V2_AUX ; 2 = GND
C14  Q_CAP  0.1UF 25V 10% X7R  pkg 0402  page 20 : 1 = P1V2_AUX ; 2 = GND
C15  Q_CAP  10UF 6.3V 20% X6S  pkg C0402  page 20 : 1 = P1V2_AUX ; 2 = GND
C16  Q_CAP  10UF 6.3V 20% X6S  pkg C0402  page 20 : 1 = P1V2_AUX ; 2 = GND
C17  Q_CAP  0.1UF 25V 10% X7R  pkg 0402  page 20 : 1 = P1V2_AUX ; 2 = GND
C18  Q_CAP  0.1UF 25V 10% X7R  pkg 0402  page 20 : 1 = P1V2_AUX ; 2 = GND
C19  Q_CAP  0.1UF 25V 10% X7R  pkg 0402  page 30 : 1 = P3V3_AUX ; 2 = GND
C20  Q_CAP  0.1UF 25V 10% X7R  pkg 0402  page 30 : 1 = P3V3_AUX ; 2 = GND
C21  Q_CAP  0.01UF 50V 10% EMPTY  pkg C0402  page 12 : 1 = P0V6_DDR_VREF_AUX ; 2 = GND
C22  Q_CAP  0.1UF 25V 10% X7R  pkg 0402  page 12 : 1 = P0V6_DDR_VREF_AUX ; 2 = GND
C23  Q_CAP  0.1UF 25V 10% X7R  pkg 0402  page 12 : 1 = P0V6_DDR_VREF_AUX ; 2 = GND
C24  Q_CAP  0.1UF 25V 10% X7R  pkg 0402  page 12 : 1 = P2E_PCH_TX_DP ; 2 = P2E_PCH_TX_C_DP
C25  Q_CAP  0.1UF 25V 10% X7R  pkg 0402  page 12 : 1 = P2E_PCH_TX_DN ; 2 = P2E_PCH_TX_C_DN
C26  Q_CAP  0.1UF 25V 10% X7R  pkg 0402  page 15 : 1 = P3V3_AUX ; 2 = GND
C27  Q_CAP  0.1UF 25V 10% X7R  pkg 0402  page 50 : 1 = LED_D22_R ; 2 = GND
C28  Q_CAP  1UF 25V 10% EMPTY  pkg C0402  page 50 : 1 = REAR_AC_PWR_BTN_N ; 2 = GND
C29  Q_CAP  0.1UF 25V 10% EMPTY  pkg 0402  page 50 : 1 = P3V3_AUX ; 2 = GND
C30  Q_CAP  1UF 25V 10% X6S  pkg C0402  page 13 : 1 = P3V3_P2V5_P1V8_RVDD ; 2 = GND
C31  Q_CAP  0.1UF 25V 10% X7R  pkg 0402  page 13 : 1 = P3V3_P2V5_P1V8_RVDD ; 2 = GND
C32  Q_CAP  1UF 25V 10% X6S  pkg C0402  page 13 : 1 = P3V3_P2V5_P1V8_RVDD ; 2 = GND
C33  Q_CAP  0.1UF 25V 10% X7R  pkg 0402  page 13 : 1 = P3V3_P2V5_P1V8_RVDD ; 2 = GND
C34  Q_CAP  0.1UF 25V 10% X7R  pkg 0402  page 22 : 1 = P3V3_AUX ; 2 = GND
C35  Q_CAP  1UF 25V 10% X6S  pkg C0402  page 15 : 1 = P3V3_P1V8_SD1VDD ; 2 = GND
C36  Q_CAP  0.1UF 25V 10% X7R  pkg 0402  page 15 : 1 = P3V3_P1V8_SD1VDD ; 2 = GND
C37  Q_CAP  0.1UF 25V 10% X7R  pkg 0402  page 15 : 1 = P3V3_RGM ; 2 = GND
C38  Q_CAP  1UF 25V 10% X6S  pkg C0402  page 15 : 1 = P3V3_P1V8_SD2VDD ; 2 = GND
C39  Q_CAP  0.1UF 25V 10% X7R  pkg 0402  page 15 : 1 = P3V3_P1V8_SD2VDD ; 2 = GND
C40  Q_CAP  4.7UF 25V 10% X6S  pkg C0603  page 15 : 1 = P1V8_BMC_USB2AV18 ; 2 = GND
C41  Q_CAP  0.1UF 25V 10% X7R  pkg 0402  page 15 : 1 = P1V8_BMC_USB2AV18 ; 2 = GND
C42  Q_CAP  22UF 6.3V 20% X6S  pkg C0603  page 15 : 1 = PVCCIO_PECI_BMC ; 2 = GND
C43  Q_CAP  1UF 25V 10% X6S  pkg C0402  page 15 : 1 = PVCCIO_PECI_BMC ; 2 = GND
C44  Q_CAP  4.7UF 25V 10% X6S  pkg C0603  page 15 : 1 = P3V3_BMC_USB2AV33 ; 2 = GND
C45  Q_CAP  0.1UF 25V 10% X7R  pkg 0402  page 15 : 1 = P3V3_BMC_USB2AV33 ; 2 = GND
C46  Q_CAP  1UF 25V 10% X6S  pkg C0402  page 17 : 1 = P1V8_STBY_AVDDPLL ; 2 = GND
C47  Q_CAP  1UF 25V 10% X6S  pkg C0402  page 17 : 1 = P1V0_STBY_RC_VCC10A ; 2 = GND
C48  Q_CAP  1UF 25V 10% X6S  pkg C0402  page 17 : 1 = P3V3_STBY_DACAV33 ; 2 = GND
C49  Q_CAP  0.1UF 25V 10% X7R  pkg 0402  page 17 : 1 = P1V8_STBY_AVDDPLL ; 2 = GND
C50  Q_CAP  0.1UF 25V 10% X7R  pkg 0402  page 17 : 1 = P1V0_STBY_RC_VCC10A ; 2 = GND
C51  Q_CAP  0.1UF 25V 10% X7R  pkg 0402  page 17 : 1 = P3V3_STBY_DACAV33 ; 2 = GND
C52  Q_CAP  1UF 25V 10% X6S  pkg C0402  page 16 : 1 = P1V0_STBY_PLAVDD ; 2 = GND
C53  Q_CAP  1UF 25V 10% X6S  pkg C0402  page 17 : 1 = P3V3_P1V8_I2C_I3C ; 2 = GND
C54  Q_CAP  0.1UF 25V 10% X7R  pkg 0402  page 16 : 1 = P1V0_STBY_PLAVDD ; 2 = GND
C55  Q_CAP  22UF 6.3V 20% X6S  pkg C0603  page 16 : 1 = P1V2_AUX ; 2 = GND
C56  Q_CAP  1UF 25V 10% X6S  pkg C0402  page 16 : 1 = P1V0_STBY_PLAVDD ; 2 = GND
C57  Q_CAP  0.1UF 25V 10% X7R  pkg 0402  page 17 : 1 = P3V3_P1V8_I2C_I3C ; 2 = GND
C58  Q_CAP  1UF 25V 10% X6S  pkg C0402  page 16 : 1 = P1V2_AUX ; 2 = GND
C59  Q_CAP  0.1UF 25V 10% X7R  pkg 0402  page 16 : 1 = P1V0_STBY_PLAVDD ; 2 = GND
C60  Q_CAP  1UF 25V 10% X6S  pkg C0402  page 17 : 1 = P3V3_STBY_PLLAHVDD ; 2 = GND
C61  Q_CAP  1UF 25V 10% X6S  pkg C0402  page 16 : 1 = P1V8_STBY_PE_VCC18A ; 2 = GND
C62  Q_CAP  1UF 25V 10% X6S  pkg C0402  page 16 : 1 = P1V2_AUX ; 2 = GND
C63  Q_CAP  2200PF 50V 10% X7R  pkg 0402  page 16 : 1 = P1V2_STBY_MVDD_CK ; 2 = GND
C64  Q_CAP  1UF 25V 10% X6S  pkg C0402  page 16 : 1 = P1V0_STBY_PLAVDD ; 2 = GND
C65  Q_CAP  0.1UF 25V 10% X7R  pkg 0402  page 17 : 1 = P3V3_STBY_PLLAHVDD ; 2 = GND
C66  Q_CAP  0.1UF 25V 10% X7R  pkg 0402  page 16 : 1 = P1V2_AUX ; 2 = GND
C67  Q_CAP  1UF 25V 10% X6S  pkg C0402  page 16 : 1 = P1V2_STBY_MVDD_CK ; 2 = GND
C68  Q_CAP  0.1UF 25V 10% X7R  pkg 0402  page 16 : 1 = P1V0_STBY_PLAVDD ; 2 = GND
C69  Q_CAP  0.1UF 25V 10% X7R  pkg 0402  page 16 : 1 = P1V8_STBY_PE_VCC18A ; 2 = GND
C70  Q_CAP  0.1UF 25V 10% X7R  pkg 0402  page 16 : 1 = P1V2_AUX ; 2 = GND
C71  Q_CAP  0.1UF 25V 10% X7R  pkg 0402  page 16 : 1 = P1V2_STBY_MVDD_CK ; 2 = GND
C72  Q_CAP  0.1UF 25V 10% X7R  pkg 0402  page 16 : 1 = P1V2_AUX ; 2 = GND
C73  Q_CAP  0.1UF 25V 10% X7R  pkg 0402  page 16 : 1 = P1V2_STBY_MVDD_CK ; 2 = GND
C74  Q_CAP  0.1UF 25V 10% X7R  pkg 0402  page 16 : 1 = P1V2_AUX ; 2 = GND
C75  Q_CAP  1UF 25V 10% X6S  pkg C0402  page 16 : 1 = A_BMC_ADCAV33 ; 2 = GND
C76  Q_CAP  0.1UF 25V 10% X7R  pkg 0402  page 16 : 1 = P1V2_AUX ; 2 = GND
C77  Q_CAP  0.1UF 25V 10% X7R  pkg 0402  page 16 : 1 = A_BMC_ADCAV33 ; 2 = GND
C78  Q_CAP  1UF 25V 10% X6S  pkg C0402  page 17 : 1 = P1V0_STBY_PE_VCC10A ; 2 = GND
C79  Q_CAP  0.1UF 25V 10% X7R  pkg 0402  page 17 : 1 = P1V0_STBY_PE_VCC10A ; 2 = GND
C80  Q_CAP  1UF 25V 10% X6S  pkg C0402  page 17 : 1 = P1V8_STBY_RC_VCC18A ; 2 = GND
C81  Q_CAP  0.1UF 25V 10% X7R  pkg 0402  page 17 : 1 = P1V8_STBY_RC_VCC18A ; 2 = GND
C82  Q_CAP  0.1UF 25V 10% X7R  pkg 0402  page 16 : 1 = P1V2_AUX ; 2 = GND
C83  Q_CAP  0.1UF 25V 10% X7R  pkg 0402  page 16 : 1 = P3V3_RTC_AUX ; 2 = GND
C84  Q_CAP  0.1UF 25V 10% X7R  pkg 0402  page 16 : 1 = P1V2_AUX ; 2 = GND
C85  Q_CAP  0.1UF 25V 10% X7R  pkg 0402  page 16 : 1 = P3V3_RGM ; 2 = GND
C86  Q_CAP  0.1UF 25V 10% X7R  pkg 0402  page 16 : 1 = P1V0_AUX ; 2 = GND
C87  Q_CAP  0.1UF 25V 10% X7R  pkg 0402  page 16 : 1 = P1V8_AUX ; 2 = GND
C88  Q_CAP  0.1UF 25V 10% X7R  pkg 0402  page 16 : 1 = P3V3_AUX ; 2 = GND
C89  Q_CAP  0.1UF 25V 10% X7R  pkg 0402  page 16 : 1 = P1V8_AUX ; 2 = GND
C90  Q_CAP  1UF 25V 10% X6S  pkg C0402  page 17 : 1 = P1V0_STBY_DP_VCC10A ; 2 = GND
C91  Q_CAP  0.1UF 25V 10% X7R  pkg 0402  page 16 : 1 = P1V2_AUX ; 2 = GND
C92  Q_CAP  0.1UF 25V 10% X7R  pkg 0402  page 16 : 1 = P1V0_AUX ; 2 = GND
C93  Q_CAP  0.1UF 25V 10% X7R  pkg 0402  page 16 : 1 = P1V8_AUX ; 2 = GND
C94  Q_CAP  0.1UF 25V 10% X7R  pkg 0402  page 16 : 1 = P3V3_AUX ; 2 = GND
C95  Q_CAP  0.1UF 25V 10% X7R  pkg 0402  page 16 : 1 = P1V8_AUX ; 2 = GND
C96  Q_CAP  0.1UF 25V 10% X7R  pkg 0402  page 17 : 1 = PGPPA_BMC_AUX ; 2 = GND
C97  Q_CAP  0.1UF 25V 10% X7R  pkg 0402  page 17 : 1 = P1V0_STBY_DP_VCC10A ; 2 = GND
C98  Q_CAP  0.1UF 25V 10% X7R  pkg 0402  page 16 : 1 = P1V2_AUX ; 2 = GND
C99  Q_CAP  0.1UF 25V 10% X7R  pkg 0402  page 16 : 1 = P1V0_AUX ; 2 = GND
C100  Q_CAP  0.1UF 25V 10% X7R  pkg 0402  page 16 : 1 = P1V8_AUX ; 2 = GND
C101  Q_CAP  0.1UF 25V 10% X7R  pkg 0402  page 16 : 1 = P3V3_AUX ; 2 = GND
C102  Q_CAP  0.1UF 25V 10% X7R  pkg 0402  page 16 : 1 = P1V8_AUX ; 2 = GND
C103  Q_CAP  0.1UF 25V 10% X7R  pkg 0402  page 16 : 1 = P1V2_AUX ; 2 = GND
C104  Q_CAP  1UF 25V 10% X6S  pkg C0402  page 16 : 1 = P1V0_AUX ; 2 = GND
C105  Q_CAP  0.1UF 25V 10% X7R  pkg 0402  page 16 : 1 = P1V8_AUX ; 2 = GND
C106  Q_CAP  1UF 25V 10% X6S  pkg C0402  page 16 : 1 = P1V8_AUX ; 2 = GND
C107  Q_CAP  0.1UF 25V 10% X7R  pkg 0402  page 16 : 1 = P1V2_AUX ; 2 = GND
C108  Q_CAP  1UF 25V 10% X6S  pkg C0402  page 16 : 1 = P1V0_AUX ; 2 = GND
C109  Q_CAP  0.1UF 25V 10% X7R  pkg 0402  page 16 : 1 = P1V8_AUX ; 2 = GND
C110  Q_CAP  1UF 25V 10% X6S  pkg C0402  page 16 : 1 = P3V3_AUX ; 2 = GND
C111  Q_CAP  1UF 25V 10% X6S  pkg C0402  page 16 : 1 = P1V8_AUX ; 2 = GND
C112  Q_CAP  0.1UF 25V 10% X7R  pkg 0402  page 16 : 1 = P1V2_AUX ; 2 = GND
C113  Q_CAP  22UF 6.3V 20% X6S  pkg C0603  page 16 : 1 = P1V0_AUX ; 2 = GND
C114  Q_CAP  1UF 25V 10% X6S  pkg C0402  page 16 : 1 = P1V8_AUX ; 2 = GND
C115  Q_CAP  1UF 25V 10% X6S  pkg C0402  page 16 : 1 = P3V3_AUX ; 2 = GND
C116  Q_CAP  1UF 25V 10% X6S  pkg C0402  page 16 : 1 = P1V8_AUX ; 2 = GND
C117  Q_CAP  1UF 25V 10% X6S  pkg C0402  page 16 : 1 = P1V2_AUX ; 2 = GND
C118  Q_CAP  22UF 6.3V 20% X6S  pkg C0603  page 16 : 1 = P1V0_AUX ; 2 = GND
C119  Q_CAP  1UF 25V 10% X6S  pkg C0402  page 16 : 1 = P1V8_AUX ; 2 = GND
C120  Q_CAP  22UF 6.3V 20% X6S  pkg C0603  page 16 : 1 = P3V3_AUX ; 2 = GND
C121  Q_CAP  22UF 6.3V 20% X6S  pkg C0603  page 16 : 1 = P1V8_AUX ; 2 = GND
C122  Q_CAP  1UF 25V 10% X6S  pkg C0402  page 16 : 1 = P1V2_AUX ; 2 = GND
C123  Q_CAP  22UF 6.3V 20% X6S  pkg C0603  page 16 : 1 = P1V0_AUX ; 2 = GND
C124  Q_CAP  22UF 6.3V 20% X6S  pkg C0603  page 16 : 1 = P1V8_AUX ; 2 = GND
C125  Q_CAP  22UF 6.3V 20% X6S  pkg C0603  page 16 : 1 = P3V3_AUX ; 2 = GND
C126  Q_CAP  22UF 6.3V 20% X6S  pkg C0603  page 16 : 1 = P1V8_AUX ; 2 = GND
C127  Q_CAP  1UF 25V 10% X6S  pkg C0402  page 16 : 1 = P1V2_AUX ; 2 = GND
C128  Q_CAP  1UF 25V 10% X6S  pkg C0402  page 17 : 1 = P1V8_STBY_DP_VCC18A ; 2 = GND
C129  Q_CAP  1UF 25V 10% X6S  pkg C0402  page 16 : 1 = P1V2_AUX ; 2 = GND
C130  Q_CAP  0.1UF 25V 10% X7R  pkg 0402  page 17 : 1 = P1V8_STBY_DP_VCC18A ; 2 = GND
C131  Q_CAP  22UF 6.3V 20% X6S  pkg C0603  page 16 : 1 = P1V2_AUX ; 2 = GND
C132  Q_CAP  22UF 6.3V 20% X6S  pkg C0603  page 16 : 1 = P1V2_AUX ; 2 = GND
C133  Q_CAP  0.01UF 50V 10% X7R  pkg C0402  page 17 : 1 = GND ; 2 = A_BMC_ADCVREFN1
C134  Q_CAP  0.01UF 50V 10% X7R  pkg C0402  page 17 : 1 = GND ; 2 = A_BMC_ADCVREFN0
C135  Q_CAP  0.01UF 50V 10% X7R  pkg C0402  page 17 : 1 = GND ; 2 = A_BMC_ADCVREFP1
C136  Q_CAP  0.01UF 50V 10% X7R  pkg C0402  page 17 : 1 = GND ; 2 = A_BMC_ADCVREFP0
C137  Q_CAP  0.01UF 50V 10% X7R  pkg C0402  page 17 : 1 = A_BMC_ADCVREFN1 ; 2 = A_BMC_ADCVREFP1
C138  Q_CAP  0.01UF 50V 10% X7R  pkg C0402  page 17 : 1 = A_BMC_ADCVREFN0 ; 2 = A_BMC_ADCVREFP0
C139  Q_CAP  0.1UF 25V 10% X7R  pkg 0402  page 17 : 1 = P1V2_P1V0_I3C_VDDL1 ; 2 = GND
C140  Q_CAP  0.1UF 25V 10% X7R  pkg 0402  page 17 : 1 = P1V2_P1V0_I3C_VDDL2 ; 2 = GND
C141  Q_CAP  0.1UF 25V 10% X7R  pkg 0402  page 41 : 1 = VCCIO1 ; 2 = GND
C142  Q_CAP  10UF 25V 10% X6S  pkg C0805  page 54 : 1 = P1V8_AUX ; 2 = GND
C143  Q_CAP  10UF 6.3V 20% X6S  pkg C0402  page 46 : 1 = P3V3_AUX ; 2 = GND
C144  Q_CAP  0.1UF 25V 10% X7R  pkg 0402  page 46 : 1 = P3V3_AUX ; 2 = GND
C145  Q_CAP  1UF 25V 10% X6S  pkg C0402  page 41 : 1 = P3V3_AUX ; 2 = GND
C146  Q_CAP  0.1UF 25V 10% X7R  pkg 0402  page 44 : 1 = P3V3_AUX ; 2 = GND
C147  Q_CAP  0.1UF 25V 10% EMPTY  pkg 0402  page 22 : 1 = P3V3_AUX ; 2 = GND
C148  Q_CAP  0.1UF 25V 10% X7R  pkg 0402  page 29 : 1 = P3V3_AUX ; 2 = GND
C149  Q_CAP  0.1UF 25V 10% X7R  pkg 0402  page 29 : 1 = P3V3_AUX ; 2 = GND
C150  Q_CAP  0.001UF 50V 10% EMPTY  pkg C0402  page 51 : 1 = PWRGD_P5V_AUX_R ; 2 = GND
C151  Q_CAP  0.001UF 50V 10% EMPTY  pkg C0402  page 52 : 1 = PWRGD_P3V3_AUX_R ; 2 = GND
C152  Q_CAP  0.1UF 25V 10% X7R  pkg 0402  page 41 : 1 = VCCIO3 ; 2 = GND
C153  Q_CAP  0.001UF 50V 10% EMPTY  pkg C0402  page 53 : 1 = PWRGD_P2V5_AUX_R ; 2 = GND
C154  Q_CAP  0.001UF 50V 10% EMPTY  pkg C0402  page 54 : 1 = PWRGD_P1V8_AUX_R ; 2 = GND
C155  Q_CAP  0.001UF 50V 10% EMPTY  pkg C0402  page 55 : 1 = PWRGD_P1V2_AUX_R ; 2 = GND
C156  Q_CAP  0.001UF 50V 10% EMPTY  pkg C0402  page 56 : 1 = PWRGD_P1V0_AUX_R ; 2 = GND
C157  Q_CAP  0.1UF 25V 10% X7R  pkg 0402  page 28 : 1 = P3V3_AUX ; 2 = GND
C158  Q_CAP  0.1UF 25V 10% X7R  pkg 0402  page 28 : 1 = P3V3_AUX ; 2 = GND
C159  Q_CAP  0.1UF 25V 10% X7R  pkg 0402  page 28 : 1 = P3V3_AUX ; 2 = GND
C160  Q_CAP  0.1UF 25V 10% X7R  pkg 0402  page 41 : 1 = VCCIO5 ; 2 = GND
C161  Q_CAP  1UF 25V 10% X6S  pkg C0402  page 22 : 1 = RST_BMC_SELF_HW_D ; 2 = RST_BMC_SELF_HW_D_C
C162  Q_CAP  0.1UF 25V 10% X7R  pkg 0402  page 41 : 1 = VCCIO4 ; 2 = GND
C163  Q_CAP  10UF 16V 20% X6S  pkg C0603  page 41 : 1 = PVCCA_AUX_PLD ; 2 = GND
C164  Q_CAP  1UF 25V 10% X6S  pkg C0402  page 41 : 1 = VCCIO1 ; 2 = GND
C165  Q_CAP  1UF 25V 10% X6S  pkg C0402  page 41 : 1 = VCCIO2 ; 2 = GND
C166  Q_CAP  1UF 25V 10% X6S  pkg C0402  page 41 : 1 = VCCIO0 ; 2 = GND
C167  Q_CAP  0.1UF 25V 10% X7R  pkg 0402  page 41 : 1 = VCCIO1 ; 2 = GND
C168  Q_CAP  0.1UF 25V 10% X7R  pkg 0402  page 20 : 1 = P0V6_DDR_VREF_AUX ; 2 = GND
C169  Q_CAP  0.01UF 50V 10% EMPTY  pkg C0402  page 20 : 1 = P1V2_AUX ; 2 = P0V6_DDR_VREF_AUX
C170  Q_CAP  0.01UF 50V 10% X7R  pkg C0402  page 20 : 1 = P0V6_DDR_VREF_AUX ; 2 = GND
C171  Q_CAP  22UF 10V 20% X6S  pkg C0805  page 28 : 1 = P5V_AUX ; 2 = GND
C172  Q_CAP  470PF 50V 10% X7R  pkg 0402  page 28 : 1 = P5V_AUX ; 2 = GND
C173  Q_CAP  2200PF 50V 10% X7R  pkg 0402  page 22 : 1 = RST_BMC_SELF_HW_D_C ; 2 = GND
C174  Q_CAP  0.1UF 25V 10% EMPTY  pkg 0402  page 10 : 1 = P3V_BAT_R ; 2 = GND
C175  Q_CAP  0.1UF 25V 10% X7R  pkg 0402  page 30 : 1 = P3V3_AUX ; 2 = GND
C176  Q_CAP  1UF 25V 10% X6S  pkg C0402  page 41 : 1 = PVCCA_AUX_PLD ; 2 = GND
C177  Q_CAP  47UF 6.3V 20% X6S  pkg C1206  page 29 : 1 = P5V_USB_REAR ; 2 = GND
C178  Q_CAP  470PF 50V 10% X7R  pkg 0402  page 29 : 1 = P5V_USB_REAR ; 2 = GND
C179  Q_CAP  470PF 50V 10% X7R  pkg 0402  page 29 : 1 = P5V_USB_REAR ; 2 = GND
C180  Q_CAP  0.1UF 25V 10% X7R  pkg 0402  page 13 : 1 = P3V3_LDO ; 2 = GND
C181  Q_CAP  0.1UF 25V 10% X7R  pkg 0402  page 50 : 1 = REAR_AC_PWR_BTN ; 2 = GND
C187  Q_CAP  0.1UF 25V 10% X7R  pkg 0402  page 41 : 1 = VCCIO2 ; 2 = GND
C188  Q_CAP  0.1UF 25V 10% X7R  pkg 0402  page 41 : 1 = VCCIO2 ; 2 = GND
C189  Q_CAP  0.1UF 25V 10% X7R  pkg 0402  page 41 : 1 = VCCIO0 ; 2 = GND
C190  Q_CAP  0.1UF 25V 10% X7R  pkg 0402  page 41 : 1 = PVCCA_AUX_PLD ; 2 = GND
C191  Q_CAP  0.1UF 25V 10% X7R  pkg 0402  page 26 : 1 = P3V3_AUX ; 2 = GND
